(kicad_pcb
	(version 20260206)
	(generator "pcbnew")
	(generator_version "10.0")
	(general
		(thickness 1.6)
		(legacy_teardrops no)
	)
	(paper "A4")
	(title_block
		(title "fcb — Lightning_FCB_BRD.brd")
		(comment 1 "Lightning (Wiwynn / Facebook NVMe JBOF) / footprints 66-72 of 495")
	)
	(layers
		(0 "F.Cu" signal "TOP")
		(4 "In1.Cu" signal "L2GND")
		(6 "In2.Cu" signal "L3VCC")
		(2 "B.Cu" signal "BOTTOM")
		(9 "F.Adhes" user "F.Adhesive")
		(11 "B.Adhes" user "B.Adhesive")
		(13 "F.Paste" user "Package Geometry/Pastemask Top")
		(15 "B.Paste" user "Package Geometry/Pastemask Bottom")
		(5 "F.SilkS" user "Ref Des/Silkscreen Top")
		(7 "B.SilkS" user "Ref Des/Silkscreen Bottom")
		(1 "F.Mask" user "Board Geometry/Soldermask Top")
		(3 "B.Mask" user "Board Geometry/Soldermask Bottom")
		(17 "Dwgs.User" user "User.Drawings")
		(19 "Cmts.User" user "User.Comments")
		(21 "Eco1.User" user "User.Eco1")
		(23 "Eco2.User" user "User.Eco2")
		(25 "Edge.Cuts" user "Board Geometry/Outline")
		(27 "Margin" user)
		(31 "F.CrtYd" user "Package Geometry/Place Bound Top")
		(29 "B.CrtYd" user "Package Geometry/Place Bound Bottom")
		(35 "F.Fab" user "Ref Des/Assembly Top")
		(33 "B.Fab" user "Ref Des/Assembly Bottom")
	)
	(footprint ""
		(layer "F.Cu")
		(at 29.718 -381 180)
		(property "Reference" "PR19"
			(at 0 0 180)
			(layer "F.SilkS")
			(hide yes)
			(effects
				(font
					(size 1.27 1.27)
				)
			)
		)
		(property "Value" "10R2F-L-GP"
			(at 0.064008 -3.993896 180)
			(unlocked yes)
			(layer "F.Fab")
			(hide yes)
			(effects
				(font
					(size 1.016 1.016)
					(thickness 0.1524)
				)
			)
		)
		(property "Device Type" "R402H14"
			(at 0.064008 -5.517896 180)
			(unlocked yes)
			(layer "F.Fab")
			(hide yes)
			(effects
				(font
					(size 1.016 1.016)
					(thickness 0.1524)
				)
			)
		)
		(duplicate_pad_numbers_are_jumpers no)
		(fp_line
			(start 0.508 -0.9398)
			(end -0.508 -0.9398)
			(stroke
				(width 0.1524)
				(type default)
			)
			(layer "F.SilkS")
		)
		(fp_line
			(start -0.508 -0.9398)
			(end -0.508 0.9398)
			(stroke
				(width 0.1524)
				(type default)
			)
			(layer "F.SilkS")
		)
		(fp_rect
			(start -0.508 0.9398)
			(end 0.508 -0.9398)
			(stroke
				(width 0)
				(type default)
			)
			(fill no)
			(layer "F.CrtYd")
		)
		(fp_rect
			(start -0.508 0.9398)
			(end 0.508 -0.9398)
			(stroke
				(width 0)
				(type default)
			)
			(fill no)
			(layer "F.Fab")
		)
		(pad "1" smd custom
			(at 0 -0.4445 180)
			(size 0.1397 0.1397)
			(layers "F.Cu" "F.Mask" "F.Paste")
			(net "ADM1276_SENSE+")
			(options
				(clearance outline)
				(anchor circle)
			)
			(primitives
				(gr_poly
					(pts
						(arc
							(start -0.1778 -0.2794)
							(mid -0.249642 -0.249642)
							(end -0.2794 -0.1778)
						)
						(arc
							(start -0.2794 0.1778)
							(mid -0.249642 0.249642)
							(end -0.1778 0.2794)
						)
						(arc
							(start 0.1778 0.2794)
							(mid 0.249642 0.249642)
							(end 0.2794 0.1778)
						)
						(arc
							(start 0.2794 -0.1778)
							(mid 0.249642 -0.249642)
							(end 0.1778 -0.2794)
						)
					)
					(width 0)
					(fill yes)
				)
			)
		)
		(pad "2" smd custom
			(at 0 0.4445 180)
			(size 0.1397 0.1397)
			(layers "F.Cu" "F.Mask" "F.Paste")
			(net "SENSE+_R2")
			(options
				(clearance outline)
				(anchor circle)
			)
			(primitives
				(gr_poly
					(pts
						(arc
							(start -0.1778 -0.2794)
							(mid -0.249642 -0.249642)
							(end -0.2794 -0.1778)
						)
						(arc
							(start -0.2794 0.1778)
							(mid -0.249642 0.249642)
							(end -0.1778 0.2794)
						)
						(arc
							(start 0.1778 0.2794)
							(mid 0.249642 0.249642)
							(end 0.2794 0.1778)
						)
						(arc
							(start 0.2794 -0.1778)
							(mid 0.249642 -0.249642)
							(end 0.1778 -0.2794)
						)
					)
					(width 0)
					(fill yes)
				)
			)
		)
	)
	(footprint ""
		(layer "F.Cu")
		(at 7.949946 -232.134918 -90)
		(property "Reference" "LED4"
			(at 0 0 270)
			(layer "F.SilkS")
			(hide yes)
			(effects
				(font
					(size 1.27 1.27)
				)
			)
		)
		(property "Value" "LED-RB-6-GP"
			(at -4.6736 3.8354 270)
			(unlocked yes)
			(layer "F.Fab")
			(hide yes)
			(effects
				(font
					(size 1.016 1.016)
					(thickness 0.1524)
				)
			)
		)
		(property "Device Type" "LED-100-3P-067106H325"
			(at -4.6736 2.3114 270)
			(unlocked yes)
			(layer "F.Fab")
			(hide yes)
			(effects
				(font
					(size 1.016 1.016)
					(thickness 0.1524)
				)
			)
		)
		(duplicate_pad_numbers_are_jumpers no)
		(fp_line
			(start -1.7526 10.414)
			(end -1.7526 6.6548)
			(stroke
				(width 0.1524)
				(type default)
			)
			(layer "F.SilkS")
		)
		(fp_line
			(start 1.7526 10.414)
			(end -1.7526 10.414)
			(stroke
				(width 0.1524)
				(type default)
			)
			(layer "F.SilkS")
		)
		(fp_line
			(start -3.6068 6.6548)
			(end -3.6068 -0.889)
			(stroke
				(width 0.1524)
				(type default)
			)
			(layer "F.SilkS")
		)
		(fp_line
			(start -1.7526 6.6548)
			(end -3.6068 6.6548)
			(stroke
				(width 0.1524)
				(type default)
			)
			(layer "F.SilkS")
		)
		(fp_line
			(start 1.7526 6.6548)
			(end 1.7526 10.414)
			(stroke
				(width 0.1524)
				(type default)
			)
			(layer "F.SilkS")
		)
		(fp_line
			(start 3.6068 6.6548)
			(end 1.7526 6.6548)
			(stroke
				(width 0.1524)
				(type default)
			)
			(layer "F.SilkS")
		)
		(fp_line
			(start -3.6068 -0.889)
			(end 3.6068 -0.889)
			(stroke
				(width 0.1524)
				(type default)
			)
			(layer "F.SilkS")
		)
		(fp_line
			(start 3.6068 -0.889)
			(end 3.6068 6.6548)
			(stroke
				(width 0.1524)
				(type default)
			)
			(layer "F.SilkS")
		)
		(fp_circle
			(center -2.54 0)
			(end -2.54 -0.9906)
			(stroke
				(width 0.3048)
				(type default)
			)
			(fill no)
			(layer "F.SilkS")
		)
		(fp_circle
			(center 0 0)
			(end 0 -0.9906)
			(stroke
				(width 0.3048)
				(type default)
			)
			(fill no)
			(layer "F.SilkS")
		)
		(fp_circle
			(center 2.54 0)
			(end 2.54 -0.9906)
			(stroke
				(width 0.3048)
				(type default)
			)
			(fill no)
			(layer "F.SilkS")
		)
		(fp_poly
			(pts
				(xy -1.4986 10.1473) (xy -1.4986 6.4008) (xy -3.3528 6.4008) (xy -3.3528 -0.3937) (xy 3.3528 -0.3937)
				(xy 3.3528 6.4008) (xy 1.4986 6.4008) (xy 1.4986 10.1473)
			)
			(stroke
				(width 0)
				(type default)
			)
			(fill no)
			(layer "F.CrtYd")
		)
		(fp_poly
			(pts
				(xy -2.0066 10.668) (xy 2.0066 10.668) (xy 2.0066 6.9088) (xy 3.8608 6.9088) (xy 3.8608 2.2098)
				(xy 3.3528 2.2098) (xy 3.3528 6.4008) (xy 1.4986 6.4008) (xy 1.4986 10.1473) (xy -1.4986 10.1473)
				(xy -1.4986 6.4008) (xy -3.3528 6.4008) (xy -3.3528 -0.3937) (xy 3.3528 -0.3937) (xy 3.3528 2.1971)
				(xy 3.8608 2.1971) (xy 3.8608 -1.143) (xy -3.8608 -1.143) (xy -3.8608 6.9088) (xy -2.0066 6.9088)
			)
			(stroke
				(width 0)
				(type default)
			)
			(fill no)
			(layer "F.CrtYd")
		)
		(fp_poly
			(pts
				(xy -2.0066 10.668) (xy -2.0066 6.9088) (xy -3.8608 6.9088) (xy -3.8608 -1.143) (xy 3.8608 -1.143)
				(xy 3.8608 6.9088) (xy 2.0066 6.9088) (xy 2.0066 10.668)
			)
			(stroke
				(width 0)
				(type default)
			)
			(fill no)
			(layer "F.Fab")
		)
		(pad "1" thru_hole circle
			(at 2.54 0 270)
			(size 1.27 1.27)
			(drill 0.889)
			(layers "*.Cu" "*.Mask")
			(remove_unused_layers no)
			(net "LED_DR_LED3_BLUE")
			(clearance 0.1651)
			(thermal_gap 0.1651)
		)
		(pad "2" thru_hole circle
			(at 0 0 270)
			(size 1.27 1.27)
			(drill 0.889)
			(layers "*.Cu" "*.Mask")
			(remove_unused_layers no)
			(net "LED_DR_LED3_K")
			(clearance 0.1651)
			(thermal_gap 0.1651)
		)
		(pad "3" thru_hole circle
			(at -2.54 0 270)
			(size 1.27 1.27)
			(drill 0.889)
			(layers "*.Cu" "*.Mask")
			(remove_unused_layers no)
			(net "LED_DR_LED3")
			(clearance 0.1651)
			(thermal_gap 0.1651)
		)
	)
	(footprint ""
		(layer "F.Cu")
		(at 17.6276 -290.703 -90)
		(property "Reference" "C43"
			(at 0 0 270)
			(layer "F.SilkS")
			(hide yes)
			(effects
				(font
					(size 1.27 1.27)
				)
			)
		)
		(property "Value" "SCD1U16V2KX-3GP"
			(at 1.1811 -2.7051 270)
			(unlocked yes)
			(layer "F.Fab")
			(hide yes)
			(effects
				(font
					(size 1.016 1.016)
					(thickness 0.1524)
				)
			)
		)
		(property "Device Type" "C402H22"
			(at 1.1811 -4.2291 270)
			(unlocked yes)
			(layer "F.Fab")
			(hide yes)
			(effects
				(font
					(size 1.016 1.016)
					(thickness 0.1524)
				)
			)
		)
		(duplicate_pad_numbers_are_jumpers no)
		(fp_rect
			(start -0.4318 0.9525)
			(end 0.4318 -0.9525)
			(stroke
				(width 0)
				(type default)
			)
			(fill no)
			(layer "F.CrtYd")
		)
		(fp_rect
			(start -0.4318 0.9525)
			(end 0.4318 -0.9525)
			(stroke
				(width 0)
				(type default)
			)
			(fill no)
			(layer "F.Fab")
		)
		(pad "1" smd custom
			(at 0 -0.4445 270)
			(size 0.1524 0.1524)
			(layers "F.Cu" "F.Mask" "F.Paste")
			(net "FAN_TACH3")
			(options
				(clearance outline)
				(anchor circle)
			)
			(primitives
				(gr_poly
					(pts
						(arc
							(start 0.3048 -0.2032)
							(mid 0.275042 -0.275042)
							(end 0.2032 -0.3048)
						)
						(arc
							(start -0.2032 -0.3048)
							(mid -0.275042 -0.275042)
							(end -0.3048 -0.2032)
						)
						(arc
							(start -0.3048 0.2032)
							(mid -0.275042 0.275042)
							(end -0.2032 0.3048)
						)
						(arc
							(start 0.2032 0.3048)
							(mid 0.275042 0.275042)
							(end 0.3048 0.2032)
						)
					)
					(width 0)
					(fill yes)
				)
			)
		)
		(pad "2" smd custom
			(at 0 0.4445 270)
			(size 0.1524 0.1524)
			(layers "F.Cu" "F.Mask" "F.Paste")
			(net "GND")
			(options
				(clearance outline)
				(anchor circle)
			)
			(primitives
				(gr_poly
					(pts
						(arc
							(start 0.3048 -0.2032)
							(mid 0.275042 -0.275042)
							(end 0.2032 -0.3048)
						)
						(arc
							(start -0.2032 -0.3048)
							(mid -0.275042 -0.275042)
							(end -0.3048 -0.2032)
						)
						(arc
							(start -0.3048 0.2032)
							(mid -0.275042 0.275042)
							(end -0.2032 0.3048)
						)
						(arc
							(start 0.2032 0.3048)
							(mid 0.275042 0.275042)
							(end 0.3048 0.2032)
						)
					)
					(width 0)
					(fill yes)
				)
			)
		)
	)
	(footprint ""
		(layer "F.Cu")
		(at 38.989 -144.3482 180)
		(property "Reference" "PR113"
			(at 0 0 180)
			(layer "F.SilkS")
			(hide yes)
			(effects
				(font
					(size 1.27 1.27)
				)
			)
		)
		(property "Value" "6K81R2F-1-GP"
			(at 0.064008 -3.993896 180)
			(unlocked yes)
			(layer "F.Fab")
			(hide yes)
			(effects
				(font
					(size 1.016 1.016)
					(thickness 0.1524)
				)
			)
		)
		(property "Device Type" "R402H16"
			(at 0.064008 -5.517896 180)
			(unlocked yes)
			(layer "F.Fab")
			(hide yes)
			(effects
				(font
					(size 1.016 1.016)
					(thickness 0.1524)
				)
			)
		)
		(duplicate_pad_numbers_are_jumpers no)
		(fp_line
			(start 0.508 -0.9398)
			(end -0.508 -0.9398)
			(stroke
				(width 0.1524)
				(type default)
			)
			(layer "F.SilkS")
		)
		(fp_line
			(start -0.508 -0.9398)
			(end -0.508 0.9398)
			(stroke
				(width 0.1524)
				(type default)
			)
			(layer "F.SilkS")
		)
		(fp_rect
			(start -0.508 0.9398)
			(end 0.508 -0.9398)
			(stroke
				(width 0)
				(type default)
			)
			(fill no)
			(layer "F.CrtYd")
		)
		(fp_rect
			(start -0.508 0.9398)
			(end 0.508 -0.9398)
			(stroke
				(width 0)
				(type default)
			)
			(fill no)
			(layer "F.Fab")
		)
		(pad "1" smd custom
			(at 0 -0.4445 180)
			(size 0.1397 0.1397)
			(layers "F.Cu" "F.Mask" "F.Paste")
			(net "P12VL_2490_EN_2")
			(options
				(clearance outline)
				(anchor circle)
			)
			(primitives
				(gr_poly
					(pts
						(arc
							(start -0.1778 -0.2794)
							(mid -0.249642 -0.249642)
							(end -0.2794 -0.1778)
						)
						(arc
							(start -0.2794 0.1778)
							(mid -0.249642 0.249642)
							(end -0.1778 0.2794)
						)
						(arc
							(start 0.1778 0.2794)
							(mid 0.249642 0.249642)
							(end 0.2794 0.1778)
						)
						(arc
							(start 0.2794 -0.1778)
							(mid 0.249642 -0.249642)
							(end 0.1778 -0.2794)
						)
					)
					(width 0)
					(fill yes)
				)
			)
		)
		(pad "2" smd custom
			(at 0 0.4445 180)
			(size 0.1397 0.1397)
			(layers "F.Cu" "F.Mask" "F.Paste")
			(net "GND")
			(options
				(clearance outline)
				(anchor circle)
			)
			(primitives
				(gr_poly
					(pts
						(arc
							(start -0.1778 -0.2794)
							(mid -0.249642 -0.249642)
							(end -0.2794 -0.1778)
						)
						(arc
							(start -0.2794 0.1778)
							(mid -0.249642 0.249642)
							(end -0.1778 0.2794)
						)
						(arc
							(start 0.1778 0.2794)
							(mid 0.249642 0.249642)
							(end 0.2794 0.1778)
						)
						(arc
							(start 0.2794 -0.1778)
							(mid 0.249642 -0.249642)
							(end 0.1778 -0.2794)
						)
					)
					(width 0)
					(fill yes)
				)
			)
		)
	)
	(footprint ""
		(layer "F.Cu")
		(at 37.846 -240.665 180)
		(property "Reference" "R157"
			(at 0 0 180)
			(layer "F.SilkS")
			(hide yes)
			(effects
				(font
					(size 1.27 1.27)
				)
			)
		)
		(property "Value" "330R2J-3-GP"
			(at 0.064008 -3.993896 180)
			(unlocked yes)
			(layer "F.Fab")
			(hide yes)
			(effects
				(font
					(size 1.016 1.016)
					(thickness 0.1524)
				)
			)
		)
		(property "Device Type" "R402H16"
			(at 0.064008 -5.517896 180)
			(unlocked yes)
			(layer "F.Fab")
			(hide yes)
			(effects
				(font
					(size 1.016 1.016)
					(thickness 0.1524)
				)
			)
		)
		(duplicate_pad_numbers_are_jumpers no)
		(fp_line
			(start 0.508 -0.9398)
			(end -0.508 -0.9398)
			(stroke
				(width 0.1524)
				(type default)
			)
			(layer "F.SilkS")
		)
		(fp_line
			(start -0.508 -0.9398)
			(end -0.508 0.9398)
			(stroke
				(width 0.1524)
				(type default)
			)
			(layer "F.SilkS")
		)
		(fp_rect
			(start -0.508 0.9398)
			(end 0.508 -0.9398)
			(stroke
				(width 0)
				(type default)
			)
			(fill no)
			(layer "F.CrtYd")
		)
		(fp_rect
			(start -0.508 0.9398)
			(end 0.508 -0.9398)
			(stroke
				(width 0)
				(type default)
			)
			(fill no)
			(layer "F.Fab")
		)
		(pad "1" smd custom
			(at 0 -0.4445 180)
			(size 0.1397 0.1397)
			(layers "F.Cu" "F.Mask" "F.Paste")
			(net "P3V3")
			(options
				(clearance outline)
				(anchor circle)
			)
			(primitives
				(gr_poly
					(pts
						(arc
							(start -0.1778 -0.2794)
							(mid -0.249642 -0.249642)
							(end -0.2794 -0.1778)
						)
						(arc
							(start -0.2794 0.1778)
							(mid -0.249642 0.249642)
							(end -0.1778 0.2794)
						)
						(arc
							(start 0.1778 0.2794)
							(mid 0.249642 0.249642)
							(end 0.2794 0.1778)
						)
						(arc
							(start 0.2794 -0.1778)
							(mid 0.249642 -0.249642)
							(end 0.1778 -0.2794)
						)
					)
					(width 0)
					(fill yes)
				)
			)
		)
		(pad "2" smd custom
			(at 0 0.4445 180)
			(size 0.1397 0.1397)
			(layers "F.Cu" "F.Mask" "F.Paste")
			(net "LED_DR_LED1")
			(options
				(clearance outline)
				(anchor circle)
			)
			(primitives
				(gr_poly
					(pts
						(arc
							(start -0.1778 -0.2794)
							(mid -0.249642 -0.249642)
							(end -0.2794 -0.1778)
						)
						(arc
							(start -0.2794 0.1778)
							(mid -0.249642 0.249642)
							(end -0.1778 0.2794)
						)
						(arc
							(start 0.1778 0.2794)
							(mid 0.249642 0.249642)
							(end 0.2794 0.1778)
						)
						(arc
							(start 0.2794 -0.1778)
							(mid 0.249642 -0.249642)
							(end 0.1778 -0.2794)
						)
					)
					(width 0)
					(fill yes)
				)
			)
		)
	)
	(footprint ""
		(layer "F.Cu")
		(at 9.9568 -87.757)
		(property "Reference" "R30"
			(at 0 0 0)
			(layer "F.SilkS")
			(hide yes)
			(effects
				(font
					(size 1.27 1.27)
				)
			)
		)
		(property "Value" "0R2J-2-GP"
			(at 0.064008 -3.993896 0)
			(unlocked yes)
			(layer "F.Fab")
			(hide yes)
			(effects
				(font
					(size 1.016 1.016)
					(thickness 0.1524)
				)
			)
		)
		(property "Device Type" "R402H16"
			(at 0.064008 -5.517896 0)
			(unlocked yes)
			(layer "F.Fab")
			(hide yes)
			(effects
				(font
					(size 1.016 1.016)
					(thickness 0.1524)
				)
			)
		)
		(duplicate_pad_numbers_are_jumpers no)
		(fp_line
			(start -0.508 -0.9398)
			(end -0.508 0.9398)
			(stroke
				(width 0.1524)
				(type default)
			)
			(layer "F.SilkS")
		)
		(fp_line
			(start 0.508 -0.9398)
			(end -0.508 -0.9398)
			(stroke
				(width 0.1524)
				(type default)
			)
			(layer "F.SilkS")
		)
		(fp_rect
			(start -0.508 0.9398)
			(end 0.508 -0.9398)
			(stroke
				(width 0)
				(type default)
			)
			(fill no)
			(layer "F.CrtYd")
		)
		(fp_rect
			(start -0.508 0.9398)
			(end 0.508 -0.9398)
			(stroke
				(width 0)
				(type default)
			)
			(fill no)
			(layer "F.Fab")
		)
		(pad "1" smd custom
			(at 0 -0.4445)
			(size 0.1397 0.1397)
			(layers "F.Cu" "F.Mask" "F.Paste")
			(net "LED_DR_LED4_K")
			(options
				(clearance outline)
				(anchor circle)
			)
			(primitives
				(gr_poly
					(pts
						(arc
							(start -0.1778 -0.2794)
							(mid -0.249642 -0.249642)
							(end -0.2794 -0.1778)
						)
						(arc
							(start -0.2794 0.1778)
							(mid -0.249642 0.249642)
							(end -0.1778 0.2794)
						)
						(arc
							(start 0.1778 0.2794)
							(mid 0.249642 0.249642)
							(end 0.2794 0.1778)
						)
						(arc
							(start 0.2794 -0.1778)
							(mid 0.249642 -0.249642)
							(end 0.1778 -0.2794)
						)
					)
					(width 0)
					(fill yes)
				)
			)
		)
		(pad "2" smd custom
			(at 0 0.4445)
			(size 0.1397 0.1397)
			(layers "F.Cu" "F.Mask" "F.Paste")
			(net "GND")
			(options
				(clearance outline)
				(anchor circle)
			)
			(primitives
				(gr_poly
					(pts
						(arc
							(start -0.1778 -0.2794)
							(mid -0.249642 -0.249642)
							(end -0.2794 -0.1778)
						)
						(arc
							(start -0.2794 0.1778)
							(mid -0.249642 0.249642)
							(end -0.1778 0.2794)
						)
						(arc
							(start 0.1778 0.2794)
							(mid 0.249642 0.249642)
							(end 0.2794 0.1778)
						)
						(arc
							(start 0.2794 -0.1778)
							(mid 0.249642 -0.249642)
							(end 0.1778 -0.2794)
						)
					)
					(width 0)
					(fill yes)
				)
			)
		)
	)
	(footprint ""
		(layer "F.Cu")
		(at 31.3182 -253.8984 180)
		(property "Reference" "R47"
			(at 0 0 180)
			(layer "F.SilkS")
			(hide yes)
			(effects
				(font
					(size 1.27 1.27)
				)
			)
		)
		(property "Value" "0R2J-2-GP"
			(at 0.064008 -3.993896 180)
			(unlocked yes)
			(layer "F.Fab")
			(hide yes)
			(effects
				(font
					(size 1.016 1.016)
					(thickness 0.1524)
				)
			)
		)
		(property "Device Type" "R402H16"
			(at 0.064008 -5.517896 180)
			(unlocked yes)
			(layer "F.Fab")
			(hide yes)
			(effects
				(font
					(size 1.016 1.016)
					(thickness 0.1524)
				)
			)
		)
		(duplicate_pad_numbers_are_jumpers no)
		(fp_line
			(start 0.508 -0.9398)
			(end -0.508 -0.9398)
			(stroke
				(width 0.1524)
				(type default)
			)
			(layer "F.SilkS")
		)
		(fp_line
			(start -0.508 -0.9398)
			(end -0.508 0.9398)
			(stroke
				(width 0.1524)
				(type default)
			)
			(layer "F.SilkS")
		)
		(fp_rect
			(start -0.508 0.9398)
			(end 0.508 -0.9398)
			(stroke
				(width 0)
				(type default)
			)
			(fill no)
			(layer "F.CrtYd")
		)
		(fp_rect
			(start -0.508 0.9398)
			(end 0.508 -0.9398)
			(stroke
				(width 0)
				(type default)
			)
			(fill no)
			(layer "F.Fab")
		)
		(pad "1" smd custom
			(at 0 -0.4445 180)
			(size 0.1397 0.1397)
			(layers "F.Cu" "F.Mask" "F.Paste")
			(net "I2C_C_SDA_EEPROM")
			(options
				(clearance outline)
				(anchor circle)
			)
			(primitives
				(gr_poly
					(pts
						(arc
							(start -0.1778 -0.2794)
							(mid -0.249642 -0.249642)
							(end -0.2794 -0.1778)
						)
						(arc
							(start -0.2794 0.1778)
							(mid -0.249642 0.249642)
							(end -0.1778 0.2794)
						)
						(arc
							(start 0.1778 0.2794)
							(mid 0.249642 0.249642)
							(end 0.2794 0.1778)
						)
						(arc
							(start 0.2794 -0.1778)
							(mid 0.249642 -0.249642)
							(end 0.1778 -0.2794)
						)
					)
					(width 0)
					(fill yes)
				)
			)
		)
		(pad "2" smd custom
			(at 0 0.4445 180)
			(size 0.1397 0.1397)
			(layers "F.Cu" "F.Mask" "F.Paste")
			(net "I2C_C_SDA")
			(options
				(clearance outline)
				(anchor circle)
			)
			(primitives
				(gr_poly
					(pts
						(arc
							(start -0.1778 -0.2794)
							(mid -0.249642 -0.249642)
							(end -0.2794 -0.1778)
						)
						(arc
							(start -0.2794 0.1778)
							(mid -0.249642 0.249642)
							(end -0.1778 0.2794)
						)
						(arc
							(start 0.1778 0.2794)
							(mid 0.249642 0.249642)
							(end 0.2794 0.1778)
						)
						(arc
							(start 0.2794 -0.1778)
							(mid 0.249642 -0.249642)
							(end 0.1778 -0.2794)
						)
					)
					(width 0)
					(fill yes)
				)
			)
		)
	)
)
